(kicad_pcb
	(version 20260206)
	(generator "pcbnew")
	(generator_version "10.0")
	(general
		(thickness 1.6)
		(legacy_teardrops no)
	)
	(paper "A4")
	(title_block
		(title "04192023_DAF0TMB3IC0_F0TG_MB_C_brd_V02_OCP.brd")
		(comment 1 "Grand Teton / footprints 927-932 of 8354")
	)
	(layers
		(0 "F.Cu" signal "TOP")
		(4 "In1.Cu" signal "GND")
		(6 "In2.Cu" signal "IN1")
		(8 "In3.Cu" signal "GND1")
		(10 "In4.Cu" signal "IN2")
		(12 "In5.Cu" signal "GND2")
		(14 "In6.Cu" signal "IN3")
		(16 "In7.Cu" signal "GND3")
		(18 "In8.Cu" signal "VCC")
		(20 "In9.Cu" signal "VCC1")
		(22 "In10.Cu" signal "GND4")
		(24 "In11.Cu" signal "IN4")
		(26 "In12.Cu" signal "GND5")
		(28 "In13.Cu" signal "IN5")
		(30 "In14.Cu" signal "GND6")
		(32 "In15.Cu" signal "IN6")
		(34 "In16.Cu" signal "GND7")
		(2 "B.Cu" signal "BOTTOM")
		(9 "F.Adhes" user "F.Adhesive")
		(11 "B.Adhes" user "B.Adhesive")
		(13 "F.Paste" user "Package Geometry/Pastemask Top")
		(15 "B.Paste" user "Package Geometry/Pastemask Bottom")
		(5 "F.SilkS" user "Ref Des/Silkscreen Top")
		(7 "B.SilkS" user "Ref Des/Silkscreen Bottom")
		(1 "F.Mask" user "Board Geometry/Soldermask Top")
		(3 "B.Mask" user "Board Geometry/Soldermask Bottom")
		(17 "Dwgs.User" user "User.Drawings")
		(19 "Cmts.User" user "User.Comments")
		(21 "Eco1.User" user "User.Eco1")
		(23 "Eco2.User" user "User.Eco2")
		(25 "Edge.Cuts" user "Board Geometry/Outline")
		(27 "Margin" user)
		(31 "F.CrtYd" user "Package Geometry/Place Bound Top")
		(29 "B.CrtYd" user "Package Geometry/Place Bound Bottom")
		(35 "F.Fab" user "Ref Des/Assembly Top")
		(33 "B.Fab" user "Ref Des/Assembly Bottom")
	)
	(footprint ""
		(layer "F.Cu")
		(at 18.702782 -133.480302)
		(property "Reference" "R3336"
			(at 0 0 0)
			(layer "F.SilkS")
			(hide yes)
			(effects
				(font
					(size 1.27 1.27)
				)
			)
		)
		(property "Value" ""
			(at 0 0 0)
			(layer "F.Fab")
			(effects
				(font
					(size 1.27 1.27)
				)
			)
		)
		(duplicate_pad_numbers_are_jumpers no)
		(fp_line
			(start -0.7874 -0.4064)
			(end 0.7874 -0.4064)
			(stroke
				(width 0.1524)
				(type default)
			)
			(layer "F.SilkS")
		)
		(fp_line
			(start -0.7874 0.4064)
			(end -0.7874 -0.4064)
			(stroke
				(width 0.1524)
				(type default)
			)
			(layer "F.SilkS")
		)
		(fp_line
			(start 0.7874 -0.4064)
			(end 0.7874 0.4064)
			(stroke
				(width 0.1524)
				(type default)
			)
			(layer "F.SilkS")
		)
		(fp_line
			(start 0.7874 0.4064)
			(end -0.7874 0.4064)
			(stroke
				(width 0.1524)
				(type default)
			)
			(layer "F.SilkS")
		)
		(fp_line
			(start -0.67945 -0.305054)
			(end -0.12065 -0.305054)
			(stroke
				(width 0.1)
				(type default)
			)
			(layer "F.Fab")
		)
		(fp_line
			(start -0.67945 0.3048)
			(end -0.67945 -0.305054)
			(stroke
				(width 0.1)
				(type default)
			)
			(layer "F.Fab")
		)
		(fp_line
			(start -0.12065 -0.305054)
			(end -0.12065 -0.2794)
			(stroke
				(width 0.1)
				(type default)
			)
			(layer "F.Fab")
		)
		(fp_line
			(start -0.12065 -0.2794)
			(end 0.12065 -0.2794)
			(stroke
				(width 0.1)
				(type default)
			)
			(layer "F.Fab")
		)
		(fp_line
			(start -0.12065 0.2794)
			(end -0.12065 0.3048)
			(stroke
				(width 0.1)
				(type default)
			)
			(layer "F.Fab")
		)
		(fp_line
			(start -0.12065 0.3048)
			(end -0.67945 0.3048)
			(stroke
				(width 0.1)
				(type default)
			)
			(layer "F.Fab")
		)
		(fp_line
			(start 0.120396 0.2794)
			(end -0.12065 0.2794)
			(stroke
				(width 0.1)
				(type default)
			)
			(layer "F.Fab")
		)
		(fp_line
			(start 0.120396 0.3048)
			(end 0.120396 0.2794)
			(stroke
				(width 0.1)
				(type default)
			)
			(layer "F.Fab")
		)
		(fp_line
			(start 0.12065 -0.3048)
			(end 0.67945 -0.3048)
			(stroke
				(width 0.1)
				(type default)
			)
			(layer "F.Fab")
		)
		(fp_line
			(start 0.12065 -0.2794)
			(end 0.12065 -0.3048)
			(stroke
				(width 0.1)
				(type default)
			)
			(layer "F.Fab")
		)
		(fp_line
			(start 0.67945 -0.3048)
			(end 0.67945 0.3048)
			(stroke
				(width 0.1)
				(type default)
			)
			(layer "F.Fab")
		)
		(fp_line
			(start 0.67945 0.3048)
			(end 0.120396 0.3048)
			(stroke
				(width 0.1)
				(type default)
			)
			(layer "F.Fab")
		)
		(pad "1" smd circle
			(at -0.40005 0)
			(size 0 0)
			(layers "F.Cu" "F.Mask" "F.Paste")
			(net "CLK_100M_BMC_RC_DN_R")
		)
		(pad "2" smd circle
			(at 0.40005 0)
			(size 0 0)
			(layers "F.Cu" "F.Mask" "F.Paste")
			(net "CLK_100M_BMC_RC_DN")
		)
	)
	(footprint ""
		(layer "F.Cu")
		(at 118.718584 -57.852056)
		(property "Reference" "R1740"
			(at 0 0 0)
			(layer "F.SilkS")
			(hide yes)
			(effects
				(font
					(size 1.27 1.27)
				)
			)
		)
		(property "Value" ""
			(at 0 0 0)
			(layer "F.Fab")
			(effects
				(font
					(size 1.27 1.27)
				)
			)
		)
		(duplicate_pad_numbers_are_jumpers no)
		(fp_line
			(start -0.7874 -0.4064)
			(end 0.7874 -0.4064)
			(stroke
				(width 0.1524)
				(type default)
			)
			(layer "F.SilkS")
		)
		(fp_line
			(start -0.7874 0.4064)
			(end -0.7874 -0.4064)
			(stroke
				(width 0.1524)
				(type default)
			)
			(layer "F.SilkS")
		)
		(fp_line
			(start 0.7874 -0.4064)
			(end 0.7874 0.4064)
			(stroke
				(width 0.1524)
				(type default)
			)
			(layer "F.SilkS")
		)
		(fp_line
			(start 0.7874 0.4064)
			(end -0.7874 0.4064)
			(stroke
				(width 0.1524)
				(type default)
			)
			(layer "F.SilkS")
		)
		(fp_line
			(start -0.67945 -0.305054)
			(end -0.12065 -0.305054)
			(stroke
				(width 0.1)
				(type default)
			)
			(layer "F.Fab")
		)
		(fp_line
			(start -0.67945 0.3048)
			(end -0.67945 -0.305054)
			(stroke
				(width 0.1)
				(type default)
			)
			(layer "F.Fab")
		)
		(fp_line
			(start -0.12065 -0.305054)
			(end -0.12065 -0.2794)
			(stroke
				(width 0.1)
				(type default)
			)
			(layer "F.Fab")
		)
		(fp_line
			(start -0.12065 -0.2794)
			(end 0.12065 -0.2794)
			(stroke
				(width 0.1)
				(type default)
			)
			(layer "F.Fab")
		)
		(fp_line
			(start -0.12065 0.2794)
			(end -0.12065 0.3048)
			(stroke
				(width 0.1)
				(type default)
			)
			(layer "F.Fab")
		)
		(fp_line
			(start -0.12065 0.3048)
			(end -0.67945 0.3048)
			(stroke
				(width 0.1)
				(type default)
			)
			(layer "F.Fab")
		)
		(fp_line
			(start 0.120396 0.2794)
			(end -0.12065 0.2794)
			(stroke
				(width 0.1)
				(type default)
			)
			(layer "F.Fab")
		)
		(fp_line
			(start 0.120396 0.3048)
			(end 0.120396 0.2794)
			(stroke
				(width 0.1)
				(type default)
			)
			(layer "F.Fab")
		)
		(fp_line
			(start 0.12065 -0.3048)
			(end 0.67945 -0.3048)
			(stroke
				(width 0.1)
				(type default)
			)
			(layer "F.Fab")
		)
		(fp_line
			(start 0.12065 -0.2794)
			(end 0.12065 -0.3048)
			(stroke
				(width 0.1)
				(type default)
			)
			(layer "F.Fab")
		)
		(fp_line
			(start 0.67945 -0.3048)
			(end 0.67945 0.3048)
			(stroke
				(width 0.1)
				(type default)
			)
			(layer "F.Fab")
		)
		(fp_line
			(start 0.67945 0.3048)
			(end 0.120396 0.3048)
			(stroke
				(width 0.1)
				(type default)
			)
			(layer "F.Fab")
		)
		(pad "1" smd circle
			(at -0.40005 0)
			(size 0 0)
			(layers "F.Cu" "F.Mask" "F.Paste")
			(net "JTAG_SCM_PLD_R_TCK")
		)
		(pad "2" smd circle
			(at 0.40005 0)
			(size 0 0)
			(layers "F.Cu" "F.Mask" "F.Paste")
			(net "JTAG_SCM_PLD_TCK")
		)
	)
	(footprint ""
		(layer "F.Cu")
		(at 120.631712 -73.296272 -0.054)
		(property "Reference" "PR6011"
			(at 0 0 359.946)
			(layer "F.SilkS")
			(hide yes)
			(effects
				(font
					(size 1.27 1.27)
				)
			)
		)
		(property "Value" ""
			(at 0 0 359.946)
			(layer "F.Fab")
			(effects
				(font
					(size 1.27 1.27)
				)
			)
		)
		(duplicate_pad_numbers_are_jumpers no)
		(fp_line
			(start -0.787525 0.40638)
			(end -0.787275 -0.40642)
			(stroke
				(width 0.1524)
				(type default)
			)
			(layer "F.SilkS")
		)
		(fp_line
			(start -0.787275 -0.40642)
			(end 0.787525 -0.40638)
			(stroke
				(width 0.1524)
				(type default)
			)
			(layer "F.SilkS")
		)
		(fp_line
			(start 0.787275 0.40642)
			(end -0.787525 0.40638)
			(stroke
				(width 0.1524)
				(type default)
			)
			(layer "F.SilkS")
		)
		(fp_line
			(start 0.787525 -0.40638)
			(end 0.787275 0.40642)
			(stroke
				(width 0.1524)
				(type default)
			)
			(layer "F.SilkS")
		)
		(fp_line
			(start -0.679417 0.304678)
			(end -0.679484 -0.305176)
			(stroke
				(width 0.1)
				(type default)
			)
			(layer "F.Fab")
		)
		(fp_line
			(start -0.679484 -0.305176)
			(end -0.120683 -0.30494)
			(stroke
				(width 0.1)
				(type default)
			)
			(layer "F.Fab")
		)
		(fp_line
			(start -0.120641 0.279514)
			(end -0.120617 0.304914)
			(stroke
				(width 0.1)
				(type default)
			)
			(layer "F.Fab")
		)
		(fp_line
			(start -0.120617 0.304914)
			(end -0.679417 0.304678)
			(stroke
				(width 0.1)
				(type default)
			)
			(layer "F.Fab")
		)
		(fp_line
			(start -0.120683 -0.30494)
			(end -0.120659 -0.279286)
			(stroke
				(width 0.1)
				(type default)
			)
			(layer "F.Fab")
		)
		(fp_line
			(start -0.120659 -0.279286)
			(end 0.120641 -0.279514)
			(stroke
				(width 0.1)
				(type default)
			)
			(layer "F.Fab")
		)
		(fp_line
			(start 0.120405 0.279287)
			(end -0.120641 0.279514)
			(stroke
				(width 0.1)
				(type default)
			)
			(layer "F.Fab")
		)
		(fp_line
			(start 0.120429 0.304687)
			(end 0.120405 0.279287)
			(stroke
				(width 0.1)
				(type default)
			)
			(layer "F.Fab")
		)
		(fp_line
			(start 0.120617 -0.304914)
			(end 0.679417 -0.304678)
			(stroke
				(width 0.1)
				(type default)
			)
			(layer "F.Fab")
		)
		(fp_line
			(start 0.120641 -0.279514)
			(end 0.120617 -0.304914)
			(stroke
				(width 0.1)
				(type default)
			)
			(layer "F.Fab")
		)
		(fp_line
			(start 0.679484 0.304922)
			(end 0.120429 0.304687)
			(stroke
				(width 0.1)
				(type default)
			)
			(layer "F.Fab")
		)
		(fp_line
			(start 0.679417 -0.304678)
			(end 0.679484 0.304922)
			(stroke
				(width 0.1)
				(type default)
			)
			(layer "F.Fab")
		)
		(pad "1" smd circle
			(at -0.40005 0 359.946)
			(size 0 0)
			(layers "F.Cu" "F.Mask" "F.Paste")
			(net "P1V2_AUX_FB")
		)
		(pad "2" smd circle
			(at 0.40005 0 359.946)
			(size 0 0)
			(layers "F.Cu" "F.Mask" "F.Paste")
			(net "GND")
		)
	)
	(footprint ""
		(layer "F.Cu")
		(at 218.567 -99.441 180)
		(property "Reference" "R9034"
			(at 0 0 180)
			(layer "F.SilkS")
			(hide yes)
			(effects
				(font
					(size 1.27 1.27)
				)
			)
		)
		(property "Value" ""
			(at 0 0 180)
			(layer "F.Fab")
			(effects
				(font
					(size 1.27 1.27)
				)
			)
		)
		(duplicate_pad_numbers_are_jumpers no)
		(fp_line
			(start 0.7874 0.4064)
			(end -0.7874 0.4064)
			(stroke
				(width 0.1524)
				(type default)
			)
			(layer "F.SilkS")
		)
		(fp_line
			(start 0.7874 -0.4064)
			(end 0.7874 0.4064)
			(stroke
				(width 0.1524)
				(type default)
			)
			(layer "F.SilkS")
		)
		(fp_line
			(start -0.7874 0.4064)
			(end -0.7874 -0.4064)
			(stroke
				(width 0.1524)
				(type default)
			)
			(layer "F.SilkS")
		)
		(fp_line
			(start -0.7874 -0.4064)
			(end 0.7874 -0.4064)
			(stroke
				(width 0.1524)
				(type default)
			)
			(layer "F.SilkS")
		)
		(fp_line
			(start 0.67945 0.3048)
			(end 0.120396 0.3048)
			(stroke
				(width 0.1)
				(type default)
			)
			(layer "F.Fab")
		)
		(fp_line
			(start 0.67945 -0.3048)
			(end 0.67945 0.3048)
			(stroke
				(width 0.1)
				(type default)
			)
			(layer "F.Fab")
		)
		(fp_line
			(start 0.12065 -0.2794)
			(end 0.12065 -0.3048)
			(stroke
				(width 0.1)
				(type default)
			)
			(layer "F.Fab")
		)
		(fp_line
			(start 0.12065 -0.3048)
			(end 0.67945 -0.3048)
			(stroke
				(width 0.1)
				(type default)
			)
			(layer "F.Fab")
		)
		(fp_line
			(start 0.120396 0.3048)
			(end 0.120396 0.2794)
			(stroke
				(width 0.1)
				(type default)
			)
			(layer "F.Fab")
		)
		(fp_line
			(start 0.120396 0.2794)
			(end -0.12065 0.2794)
			(stroke
				(width 0.1)
				(type default)
			)
			(layer "F.Fab")
		)
		(fp_line
			(start -0.12065 0.3048)
			(end -0.67945 0.3048)
			(stroke
				(width 0.1)
				(type default)
			)
			(layer "F.Fab")
		)
		(fp_line
			(start -0.12065 0.2794)
			(end -0.12065 0.3048)
			(stroke
				(width 0.1)
				(type default)
			)
			(layer "F.Fab")
		)
		(fp_line
			(start -0.12065 -0.2794)
			(end 0.12065 -0.2794)
			(stroke
				(width 0.1)
				(type default)
			)
			(layer "F.Fab")
		)
		(fp_line
			(start -0.12065 -0.305054)
			(end -0.12065 -0.2794)
			(stroke
				(width 0.1)
				(type default)
			)
			(layer "F.Fab")
		)
		(fp_line
			(start -0.67945 0.3048)
			(end -0.67945 -0.305054)
			(stroke
				(width 0.1)
				(type default)
			)
			(layer "F.Fab")
		)
		(fp_line
			(start -0.67945 -0.305054)
			(end -0.12065 -0.305054)
			(stroke
				(width 0.1)
				(type default)
			)
			(layer "F.Fab")
		)
		(pad "1" smd circle
			(at -0.40005 0 180)
			(size 0 0)
			(layers "F.Cu" "F.Mask" "F.Paste")
			(net "OCP_V3_1_P3V3_R3_PWRGD")
		)
		(pad "2" smd circle
			(at 0.40005 0 180)
			(size 0 0)
			(layers "F.Cu" "F.Mask" "F.Paste")
			(net "HP_LVC3_OCP_V3_1_PWRGD_R1")
		)
	)
	(footprint ""
		(layer "F.Cu")
		(at 345.941904 -156.487622 90)
		(property "Reference" "PC161"
			(at 0 0 90)
			(layer "F.SilkS")
			(hide yes)
			(effects
				(font
					(size 1.27 1.27)
				)
			)
		)
		(property "Value" ""
			(at 0 0 90)
			(layer "F.Fab")
			(effects
				(font
					(size 1.27 1.27)
				)
			)
		)
		(duplicate_pad_numbers_are_jumpers no)
		(fp_line
			(start 0.7874 -0.4064)
			(end 0.7874 0.4064)
			(stroke
				(width 0.1524)
				(type default)
			)
			(layer "F.SilkS")
		)
		(fp_line
			(start -0.7874 -0.4064)
			(end 0.7874 -0.4064)
			(stroke
				(width 0.1524)
				(type default)
			)
			(layer "F.SilkS")
		)
		(fp_line
			(start 0.7874 0.4064)
			(end -0.7874 0.4064)
			(stroke
				(width 0.1524)
				(type default)
			)
			(layer "F.SilkS")
		)
		(fp_line
			(start -0.7874 0.4064)
			(end -0.7874 -0.4064)
			(stroke
				(width 0.1524)
				(type default)
			)
			(layer "F.SilkS")
		)
		(fp_line
			(start -0.12065 -0.305054)
			(end -0.12065 -0.2794)
			(stroke
				(width 0.1)
				(type default)
			)
			(layer "F.Fab")
		)
		(fp_line
			(start -0.67945 -0.305054)
			(end -0.12065 -0.305054)
			(stroke
				(width 0.1)
				(type default)
			)
			(layer "F.Fab")
		)
		(fp_line
			(start 0.67945 -0.3048)
			(end 0.67945 0.3048)
			(stroke
				(width 0.1)
				(type default)
			)
			(layer "F.Fab")
		)
		(fp_line
			(start 0.12065 -0.3048)
			(end 0.67945 -0.3048)
			(stroke
				(width 0.1)
				(type default)
			)
			(layer "F.Fab")
		)
		(fp_line
			(start 0.12065 -0.2794)
			(end 0.12065 -0.3048)
			(stroke
				(width 0.1)
				(type default)
			)
			(layer "F.Fab")
		)
		(fp_line
			(start -0.12065 -0.2794)
			(end 0.12065 -0.2794)
			(stroke
				(width 0.1)
				(type default)
			)
			(layer "F.Fab")
		)
		(fp_line
			(start 0.120396 0.2794)
			(end -0.12065 0.2794)
			(stroke
				(width 0.1)
				(type default)
			)
			(layer "F.Fab")
		)
		(fp_line
			(start -0.12065 0.2794)
			(end -0.12065 0.3048)
			(stroke
				(width 0.1)
				(type default)
			)
			(layer "F.Fab")
		)
		(fp_line
			(start 0.67945 0.3048)
			(end 0.120396 0.3048)
			(stroke
				(width 0.1)
				(type default)
			)
			(layer "F.Fab")
		)
		(fp_line
			(start 0.120396 0.3048)
			(end 0.120396 0.2794)
			(stroke
				(width 0.1)
				(type default)
			)
			(layer "F.Fab")
		)
		(fp_line
			(start -0.12065 0.3048)
			(end -0.67945 0.3048)
			(stroke
				(width 0.1)
				(type default)
			)
			(layer "F.Fab")
		)
		(fp_line
			(start -0.67945 0.3048)
			(end -0.67945 -0.305054)
			(stroke
				(width 0.1)
				(type default)
			)
			(layer "F.Fab")
		)
		(pad "1" smd circle
			(at -0.40005 0 90)
			(size 0 0)
			(layers "F.Cu" "F.Mask" "F.Paste")
			(net "SW_PVDDCR_CPU0_P0_BOOT6_RC")
		)
		(pad "2" smd circle
			(at 0.40005 0 90)
			(size 0 0)
			(layers "F.Cu" "F.Mask" "F.Paste")
			(net "SW_PVDDCR_CPU0_P0_PH6")
		)
	)
	(footprint ""
		(layer "F.Cu")
		(at 319.905888 -22.571456 -90)
		(property "Reference" "R131"
			(at 0 0 270)
			(layer "F.SilkS")
			(hide yes)
			(effects
				(font
					(size 1.27 1.27)
				)
			)
		)
		(property "Value" ""
			(at 0 0 270)
			(layer "F.Fab")
			(effects
				(font
					(size 1.27 1.27)
				)
			)
		)
		(duplicate_pad_numbers_are_jumpers no)
		(fp_line
			(start -0.7874 0.4064)
			(end -0.7874 -0.4064)
			(stroke
				(width 0.1524)
				(type default)
			)
			(layer "F.SilkS")
		)
		(fp_line
			(start 0.7874 0.4064)
			(end -0.7874 0.4064)
			(stroke
				(width 0.1524)
				(type default)
			)
			(layer "F.SilkS")
		)
		(fp_line
			(start -0.7874 -0.4064)
			(end 0.7874 -0.4064)
			(stroke
				(width 0.1524)
				(type default)
			)
			(layer "F.SilkS")
		)
		(fp_line
			(start 0.7874 -0.4064)
			(end 0.7874 0.4064)
			(stroke
				(width 0.1524)
				(type default)
			)
			(layer "F.SilkS")
		)
		(fp_line
			(start -0.67945 0.3048)
			(end -0.67945 -0.305054)
			(stroke
				(width 0.1)
				(type default)
			)
			(layer "F.Fab")
		)
		(fp_line
			(start -0.12065 0.3048)
			(end -0.67945 0.3048)
			(stroke
				(width 0.1)
				(type default)
			)
			(layer "F.Fab")
		)
		(fp_line
			(start 0.120396 0.3048)
			(end 0.120396 0.2794)
			(stroke
				(width 0.1)
				(type default)
			)
			(layer "F.Fab")
		)
		(fp_line
			(start 0.67945 0.3048)
			(end 0.120396 0.3048)
			(stroke
				(width 0.1)
				(type default)
			)
			(layer "F.Fab")
		)
		(fp_line
			(start -0.12065 0.2794)
			(end -0.12065 0.3048)
			(stroke
				(width 0.1)
				(type default)
			)
			(layer "F.Fab")
		)
		(fp_line
			(start 0.120396 0.2794)
			(end -0.12065 0.2794)
			(stroke
				(width 0.1)
				(type default)
			)
			(layer "F.Fab")
		)
		(fp_line
			(start -0.12065 -0.2794)
			(end 0.12065 -0.2794)
			(stroke
				(width 0.1)
				(type default)
			)
			(layer "F.Fab")
		)
		(fp_line
			(start 0.12065 -0.2794)
			(end 0.12065 -0.3048)
			(stroke
				(width 0.1)
				(type default)
			)
			(layer "F.Fab")
		)
		(fp_line
			(start 0.12065 -0.3048)
			(end 0.67945 -0.3048)
			(stroke
				(width 0.1)
				(type default)
			)
			(layer "F.Fab")
		)
		(fp_line
			(start 0.67945 -0.3048)
			(end 0.67945 0.3048)
			(stroke
				(width 0.1)
				(type default)
			)
			(layer "F.Fab")
		)
		(fp_line
			(start -0.67945 -0.305054)
			(end -0.12065 -0.305054)
			(stroke
				(width 0.1)
				(type default)
			)
			(layer "F.Fab")
		)
		(fp_line
			(start -0.12065 -0.305054)
			(end -0.12065 -0.2794)
			(stroke
				(width 0.1)
				(type default)
			)
			(layer "F.Fab")
		)
		(pad "1" smd circle
			(at -0.40005 0 270)
			(size 0 0)
			(layers "F.Cu" "F.Mask" "F.Paste")
			(net "P3V3_AUX")
		)
		(pad "2" smd circle
			(at 0.40005 0 270)
			(size 0 0)
			(layers "F.Cu" "F.Mask" "F.Paste")
			(net "UART_VCC_J8")
		)
	)
)
